(kicad_pcb
	(version 20260206)
	(generator "pcbnew")
	(generator_version "10.0")
	(general
		(thickness 1.6)
		(legacy_teardrops no)
	)
	(paper "A4")
	(title_block
		(title "9052_F0T_PDB_Converter_Brick_F_V03_1208_1600_OCP.brd")
		(comment 1 "Grand Teton / footprints 139-140 of 578")
	)
	(layers
		(0 "F.Cu" signal "TOP")
		(4 "In1.Cu" signal "GND")
		(6 "In2.Cu" signal "IN1")
		(8 "In3.Cu" signal "GND1")
		(10 "In4.Cu" signal "VCC")
		(12 "In5.Cu" signal "VCC1")
		(14 "In6.Cu" signal "GND2")
		(16 "In7.Cu" signal "IN2")
		(18 "In8.Cu" signal "GND3")
		(2 "B.Cu" signal "BOTTOM")
		(9 "F.Adhes" user "F.Adhesive")
		(11 "B.Adhes" user "B.Adhesive")
		(13 "F.Paste" user "Package Geometry/Pastemask Top")
		(15 "B.Paste" user "Package Geometry/Pastemask Bottom")
		(5 "F.SilkS" user "Ref Des/Silkscreen Top")
		(7 "B.SilkS" user "Ref Des/Silkscreen Bottom")
		(1 "F.Mask" user "Board Geometry/Soldermask Top")
		(3 "B.Mask" user "Board Geometry/Soldermask Bottom")
		(17 "Dwgs.User" user "User.Drawings")
		(19 "Cmts.User" user "User.Comments")
		(21 "Eco1.User" user "User.Eco1")
		(23 "Eco2.User" user "User.Eco2")
		(25 "Edge.Cuts" user "Board Geometry/Outline")
		(27 "Margin" user)
		(31 "F.CrtYd" user "Package Geometry/Place Bound Top")
		(29 "B.CrtYd" user "Package Geometry/Place Bound Bottom")
		(35 "F.Fab" user "Ref Des/Assembly Top")
		(33 "B.Fab" user "Ref Des/Assembly Bottom")
	)
	(footprint ""
		(layer "F.Cu")
		(at 73.66 -49.911)
		(property "Reference" "PC95"
			(at 0 0 0)
			(layer "F.SilkS")
			(hide yes)
			(effects
				(font
					(size 1.27 1.27)
				)
			)
		)
		(property "Value" ""
			(at 0 0 0)
			(layer "F.Fab")
			(effects
				(font
					(size 1.27 1.27)
				)
			)
		)
		(duplicate_pad_numbers_are_jumpers no)
		(fp_line
			(start -1.524 -0.762)
			(end 1.524 -0.762)
			(stroke
				(width 0.1524)
				(type default)
			)
			(layer "F.SilkS")
		)
		(fp_line
			(start -1.524 0.762)
			(end -1.524 -0.762)
			(stroke
				(width 0.1524)
				(type default)
			)
			(layer "F.SilkS")
		)
		(fp_line
			(start 1.524 -0.762)
			(end 1.524 0.762)
			(stroke
				(width 0.1524)
				(type default)
			)
			(layer "F.SilkS")
		)
		(fp_line
			(start 1.524 0.762)
			(end -1.524 0.762)
			(stroke
				(width 0.1524)
				(type default)
			)
			(layer "F.SilkS")
		)
		(fp_line
			(start -1.1049 -0.724916)
			(end -1.1049 0.724916)
			(stroke
				(width 0.1)
				(type default)
			)
			(layer "F.Fab")
		)
		(fp_line
			(start -1.1049 0.724916)
			(end 1.1049 0.724916)
			(stroke
				(width 0.1)
				(type default)
			)
			(layer "F.Fab")
		)
		(fp_line
			(start 1.1049 -0.724916)
			(end -1.1049 -0.724916)
			(stroke
				(width 0.1)
				(type default)
			)
			(layer "F.Fab")
		)
		(fp_line
			(start 1.1049 0.724916)
			(end 1.1049 -0.724916)
			(stroke
				(width 0.1)
				(type default)
			)
			(layer "F.Fab")
		)
		(pad "1" smd rect
			(at -0.889 0 180)
			(size 1.016 1.27)
			(layers "F.Cu" "F.Mask" "F.Paste")
			(net "P12V_BRICK")
		)
		(pad "2" smd rect
			(at 0.889 0 180)
			(size 1.016 1.27)
			(layers "F.Cu" "F.Mask" "F.Paste")
			(net "GND")
		)
	)
	(footprint ""
		(layer "F.Cu")
		(at 75.375008 -40.55999 90)
		(property "Reference" "J2"
			(at 7.41934 63.435992 0)
			(unlocked yes)
			(layer "F.SilkS")
			(effects
				(font
					(size 0.7874 0.5842)
					(thickness 0.1524)
				)
				(justify left)
			)
		)
		(property "Value" ""
			(at 0 0 90)
			(layer "F.Fab")
			(effects
				(font
					(size 1.27 1.27)
				)
			)
		)
		(duplicate_pad_numbers_are_jumpers no)
		(fp_line
			(start 6.480048 -17.85493)
			(end 6.480048 64.84493)
			(stroke
				(width 0.1524)
				(type default)
			)
			(layer "F.SilkS")
		)
		(fp_line
			(start -14.100048 -17.85493)
			(end 6.480048 -17.85493)
			(stroke
				(width 0.1524)
				(type default)
			)
			(layer "F.SilkS")
		)
		(fp_line
			(start 3.480054 -14.854936)
			(end 3.480054 61.844936)
			(stroke
				(width 0.1524)
				(type default)
			)
			(layer "F.SilkS")
		)
		(fp_line
			(start -5.6769 -14.854936)
			(end 3.480054 -14.854936)
			(stroke
				(width 0.1524)
				(type default)
			)
			(layer "F.SilkS")
		)
		(fp_line
			(start -11.100054 -14.854936)
			(end -9.5631 -14.854936)
			(stroke
				(width 0.1524)
				(type default)
			)
			(layer "F.SilkS")
		)
		(fp_line
			(start 3.480054 61.844936)
			(end -5.6769 61.844936)
			(stroke
				(width 0.1524)
				(type default)
			)
			(layer "F.SilkS")
		)
		(fp_line
			(start -9.5504 61.844936)
			(end -11.100054 61.844936)
			(stroke
				(width 0.1524)
				(type default)
			)
			(layer "F.SilkS")
		)
		(fp_line
			(start -11.100054 61.844936)
			(end -11.100054 -14.854936)
			(stroke
				(width 0.1524)
				(type default)
			)
			(layer "F.SilkS")
		)
		(fp_line
			(start 6.480048 64.84493)
			(end -14.100048 64.84493)
			(stroke
				(width 0.1524)
				(type default)
			)
			(layer "F.SilkS")
		)
		(fp_line
			(start -14.100048 64.84493)
			(end -14.100048 -17.85493)
			(stroke
				(width 0.1524)
				(type default)
			)
			(layer "F.SilkS")
		)
		(fp_poly
			(pts
				(xy 5.0038 -0.508) (xy 5.0038 0.508) (xy 3.9878 0)
			)
			(stroke
				(width 0)
				(type default)
			)
			(fill yes)
			(layer "F.SilkS")
		)
		(fp_line
			(start 6.480048 -17.85493)
			(end 6.480048 64.84493)
			(stroke
				(width 0.1524)
				(type default)
			)
			(layer "B.SilkS")
		)
		(fp_line
			(start -14.100048 -17.85493)
			(end 6.480048 -17.85493)
			(stroke
				(width 0.1524)
				(type default)
			)
			(layer "B.SilkS")
		)
		(fp_line
			(start 6.480048 64.84493)
			(end -14.100048 64.84493)
			(stroke
				(width 0.1524)
				(type default)
			)
			(layer "B.SilkS")
		)
		(fp_line
			(start -14.100048 64.84493)
			(end -14.100048 -17.85493)
			(stroke
				(width 0.1524)
				(type default)
			)
			(layer "B.SilkS")
		)
		(fp_line
			(start 6.480048 -17.85493)
			(end 6.480048 64.84493)
			(stroke
				(width 0.1)
				(type default)
			)
			(layer "B.Fab")
		)
		(fp_line
			(start -14.100048 -17.85493)
			(end 6.480048 -17.85493)
			(stroke
				(width 0.1)
				(type default)
			)
			(layer "B.Fab")
		)
		(fp_line
			(start 6.480048 64.84493)
			(end -14.100048 64.84493)
			(stroke
				(width 0.1)
				(type default)
			)
			(layer "B.Fab")
		)
		(fp_line
			(start -14.100048 64.84493)
			(end -14.100048 -17.85493)
			(stroke
				(width 0.1)
				(type default)
			)
			(layer "B.Fab")
		)
		(fp_line
			(start 3.480054 -14.854936)
			(end 3.480054 61.844936)
			(stroke
				(width 0.1)
				(type default)
			)
			(layer "F.Fab")
		)
		(fp_line
			(start -11.100054 -14.854936)
			(end 3.480054 -14.854936)
			(stroke
				(width 0.1)
				(type default)
			)
			(layer "F.Fab")
		)
		(fp_line
			(start 3.480054 61.844936)
			(end -11.100054 61.844936)
			(stroke
				(width 0.1)
				(type default)
			)
			(layer "F.Fab")
		)
		(fp_line
			(start -11.100054 61.844936)
			(end -11.100054 -14.854936)
			(stroke
				(width 0.1)
				(type default)
			)
			(layer "F.Fab")
		)
		(fp_poly
			(pts
				(xy 5.0038 -0.508) (xy 5.0038 0.508) (xy 3.9878 0)
			)
			(stroke
				(width 0)
				(type default)
			)
			(fill yes)
			(layer "F.Fab")
		)
		(fp_text user "PRESS-FIT"
			(at 4.98475 15.1257 0)
			(unlocked yes)
			(layer "F.SilkS")
			(effects
				(font
					(size 1.905 1.4224)
					(thickness 0.1524)
				)
				(justify left)
			)
		)
		(fp_text user "PRESS-FIT"
			(at 5.01015 31.7881 0)
			(unlocked yes)
			(layer "B.SilkS")
			(effects
				(font
					(size 1.905 1.4224)
					(thickness 0.1524)
				)
				(justify left mirror)
			)
		)
		(fp_text user "PRESS-FIT"
			(at 5.01015 31.7881 0)
			(unlocked yes)
			(layer "B.Fab")
			(effects
				(font
					(size 1.905 1.4224)
					(thickness 0.1524)
				)
				(justify left mirror)
			)
		)
		(fp_text user "PRESS-FIT"
			(at 4.98475 15.1257 0)
			(unlocked yes)
			(layer "F.Fab")
			(effects
				(font
					(size 1.905 1.4224)
					(thickness 0.1524)
				)
				(justify left)
			)
		)
		(pad "" np_thru_hole circle
			(at -7.62 -12.065)
			(size 0 0)
			(drill 3.2004)
			(layers "*.Cu" "*.Mask")
			(clearance 0)
		)
		(pad "" np_thru_hole circle
			(at -7.62 59.055)
			(size 0 0)
			(drill 3.2004)
			(layers "*.Cu" "*.Mask")
			(clearance 0)
		)
		(pad "P1_1" thru_hole rect
			(at 0 0)
			(size 1.52781 1.52781)
			(drill 1.01981)
			(layers "*.Cu" "*.Mask")
			(remove_unused_layers no)
			(net "GND")
			(clearance 0)
			(padstack
				(mode front_inner_back)
				(layer "Inner"
					(shape circle)
					(size 1.52781 1.52781)
					(clearance 0)
				)
				(layer "B.Cu"
					(shape rect)
					(size 1.52781 1.52781)
					(clearance 0)
				)
			)
		)
		(pad "P1_2" thru_hole circle
			(at -2.54 0)
			(size 1.52781 1.52781)
			(drill 1.01981)
			(layers "*.Cu" "*.Mask")
			(remove_unused_layers no)
			(net "GND")
			(clearance 0)
		)
		(pad "P1_3" thru_hole circle
			(at -5.08 0)
			(size 1.52781 1.52781)
			(drill 1.01981)
			(layers "*.Cu" "*.Mask")
			(remove_unused_layers no)
			(net "GND")
			(clearance 0)
		)
		(pad "P1_4" thru_hole circle
			(at -7.62 0)
			(size 1.52781 1.52781)
			(drill 1.01981)
			(layers "*.Cu" "*.Mask")
			(remove_unused_layers no)
			(net "GND")
			(clearance 0)
		)
		(pad "P1_5" thru_hole circle
			(at 0 2.54)
			(size 1.52781 1.52781)
			(drill 1.01981)
			(layers "*.Cu" "*.Mask")
			(remove_unused_layers no)
			(net "GND")
			(clearance 0)
		)
		(pad "P1_6" thru_hole circle
			(at -2.54 2.54)
			(size 1.52781 1.52781)
			(drill 1.01981)
			(layers "*.Cu" "*.Mask")
			(remove_unused_layers no)
			(net "GND")
			(clearance 0)
		)
		(pad "P1_7" thru_hole circle
			(at -5.08 2.54)
			(size 1.52781 1.52781)
			(drill 1.01981)
			(layers "*.Cu" "*.Mask")
			(remove_unused_layers no)
			(net "GND")
			(clearance 0)
		)
		(pad "P1_8" thru_hole circle
			(at -7.62 2.54)
			(size 1.52781 1.52781)
			(drill 1.01981)
			(layers "*.Cu" "*.Mask")
			(remove_unused_layers no)
			(net "GND")
			(clearance 0)
		)
		(pad "P2_1" thru_hole circle
			(at 0 8.89)
			(size 1.52781 1.52781)
			(drill 1.01981)
			(layers "*.Cu" "*.Mask")
			(remove_unused_layers no)
			(net "GND")
			(clearance 0)
		)
		(pad "P2_2" thru_hole circle
			(at -2.54 8.89)
			(size 1.52781 1.52781)
			(drill 1.01981)
			(layers "*.Cu" "*.Mask")
			(remove_unused_layers no)
			(net "GND")
			(clearance 0)
		)
		(pad "P2_3" thru_hole circle
			(at -5.08 8.89)
			(size 1.52781 1.52781)
			(drill 1.01981)
			(layers "*.Cu" "*.Mask")
			(remove_unused_layers no)
			(net "GND")
			(clearance 0)
		)
		(pad "P2_4" thru_hole circle
			(at -7.62 8.89)
			(size 1.52781 1.52781)
			(drill 1.01981)
			(layers "*.Cu" "*.Mask")
			(remove_unused_layers no)
			(net "GND")
			(clearance 0)
		)
		(pad "P2_5" thru_hole circle
			(at 0 11.43)
			(size 1.52781 1.52781)
			(drill 1.01981)
			(layers "*.Cu" "*.Mask")
			(remove_unused_layers no)
			(net "GND")
			(clearance 0)
		)
		(pad "P2_6" thru_hole circle
			(at -2.54 11.43)
			(size 1.52781 1.52781)
			(drill 1.01981)
			(layers "*.Cu" "*.Mask")
			(remove_unused_layers no)
			(net "GND")
			(clearance 0)
		)
		(pad "P2_7" thru_hole circle
			(at -5.08 11.43)
			(size 1.52781 1.52781)
			(drill 1.01981)
			(layers "*.Cu" "*.Mask")
			(remove_unused_layers no)
			(net "GND")
			(clearance 0)
		)
		(pad "P2_8" thru_hole circle
			(at -7.62 11.43)
			(size 1.52781 1.52781)
			(drill 1.01981)
			(layers "*.Cu" "*.Mask")
			(remove_unused_layers no)
			(net "GND")
			(clearance 0)
		)
		(pad "P3_1" thru_hole circle
			(at 0 17.78)
			(size 1.52781 1.52781)
			(drill 1.01981)
			(layers "*.Cu" "*.Mask")
			(remove_unused_layers no)
			(net "GND")
			(clearance 0)
		)
		(pad "P3_2" thru_hole circle
			(at -2.54 17.78)
			(size 1.52781 1.52781)
			(drill 1.01981)
			(layers "*.Cu" "*.Mask")
			(remove_unused_layers no)
			(net "GND")
			(clearance 0)
		)
		(pad "P3_3" thru_hole circle
			(at -5.08 17.78)
			(size 1.52781 1.52781)
			(drill 1.01981)
			(layers "*.Cu" "*.Mask")
			(remove_unused_layers no)
			(net "GND")
			(clearance 0)
		)
		(pad "P3_4" thru_hole circle
			(at -7.62 17.78)
			(size 1.52781 1.52781)
			(drill 1.01981)
			(layers "*.Cu" "*.Mask")
			(remove_unused_layers no)
			(net "GND")
			(clearance 0)
		)
		(pad "P3_5" thru_hole circle
			(at 0 20.32)
			(size 1.52781 1.52781)
			(drill 1.01981)
			(layers "*.Cu" "*.Mask")
			(remove_unused_layers no)
			(net "GND")
			(clearance 0)
		)
		(pad "P3_6" thru_hole circle
			(at -2.54 20.32)
			(size 1.52781 1.52781)
			(drill 1.01981)
			(layers "*.Cu" "*.Mask")
			(remove_unused_layers no)
			(net "GND")
			(clearance 0)
		)
		(pad "P3_7" thru_hole circle
			(at -5.08 20.32)
			(size 1.52781 1.52781)
			(drill 1.01981)
			(layers "*.Cu" "*.Mask")
			(remove_unused_layers no)
			(net "GND")
			(clearance 0)
		)
		(pad "P3_8" thru_hole circle
			(at -7.62 20.32)
			(size 1.52781 1.52781)
			(drill 1.01981)
			(layers "*.Cu" "*.Mask")
			(remove_unused_layers no)
			(net "GND")
			(clearance 0)
		)
		(pad "P4_1" thru_hole circle
			(at 0 26.67)
			(size 1.52781 1.52781)
			(drill 1.01981)
			(layers "*.Cu" "*.Mask")
			(remove_unused_layers no)
			(net "P12V_BRICK")
			(clearance 0)
		)
		(pad "P4_2" thru_hole circle
			(at -2.54 26.67)
			(size 1.52781 1.52781)
			(drill 1.01981)
			(layers "*.Cu" "*.Mask")
			(remove_unused_layers no)
			(net "P12V_BRICK")
			(clearance 0)
		)
		(pad "P4_3" thru_hole circle
			(at -5.08 26.67)
			(size 1.52781 1.52781)
			(drill 1.01981)
			(layers "*.Cu" "*.Mask")
			(remove_unused_layers no)
			(net "P12V_BRICK")
			(clearance 0)
		)
		(pad "P4_4" thru_hole circle
			(at -7.62 26.67)
			(size 1.52781 1.52781)
			(drill 1.01981)
			(layers "*.Cu" "*.Mask")
			(remove_unused_layers no)
			(net "P12V_BRICK")
			(clearance 0)
		)
		(pad "P4_5" thru_hole circle
			(at 0 29.21)
			(size 1.52781 1.52781)
			(drill 1.01981)
			(layers "*.Cu" "*.Mask")
			(remove_unused_layers no)
			(net "P12V_BRICK")
			(clearance 0)
		)
		(pad "P4_6" thru_hole circle
			(at -2.54 29.21)
			(size 1.52781 1.52781)
			(drill 1.01981)
			(layers "*.Cu" "*.Mask")
			(remove_unused_layers no)
			(net "P12V_BRICK")
			(clearance 0)
		)
		(pad "P4_7" thru_hole circle
			(at -5.08 29.21)
			(size 1.52781 1.52781)
			(drill 1.01981)
			(layers "*.Cu" "*.Mask")
			(remove_unused_layers no)
			(net "P12V_BRICK")
			(clearance 0)
		)
		(pad "P4_8" thru_hole circle
			(at -7.62 29.21)
			(size 1.52781 1.52781)
			(drill 1.01981)
			(layers "*.Cu" "*.Mask")
			(remove_unused_layers no)
			(net "P12V_BRICK")
			(clearance 0)
		)
		(pad "P5_1" thru_hole circle
			(at 0 35.56)
			(size 1.52781 1.52781)
			(drill 1.01981)
			(layers "*.Cu" "*.Mask")
			(remove_unused_layers no)
			(net "P12V_BRICK")
			(clearance 0)
		)
		(pad "P5_2" thru_hole circle
			(at -2.54 35.56)
			(size 1.52781 1.52781)
			(drill 1.01981)
			(layers "*.Cu" "*.Mask")
			(remove_unused_layers no)
			(net "P12V_BRICK")
			(clearance 0)
		)
		(pad "P5_3" thru_hole circle
			(at -5.08 35.56)
			(size 1.52781 1.52781)
			(drill 1.01981)
			(layers "*.Cu" "*.Mask")
			(remove_unused_layers no)
			(net "P12V_BRICK")
			(clearance 0)
		)
		(pad "P5_4" thru_hole circle
			(at -7.62 35.56)
			(size 1.52781 1.52781)
			(drill 1.01981)
			(layers "*.Cu" "*.Mask")
			(remove_unused_layers no)
			(net "P12V_BRICK")
			(clearance 0)
		)
		(pad "P5_5" thru_hole circle
			(at 0 38.1)
			(size 1.52781 1.52781)
			(drill 1.01981)
			(layers "*.Cu" "*.Mask")
			(remove_unused_layers no)
			(net "P12V_BRICK")
			(clearance 0)
		)
		(pad "P5_6" thru_hole circle
			(at -2.54 38.1)
			(size 1.52781 1.52781)
			(drill 1.01981)
			(layers "*.Cu" "*.Mask")
			(remove_unused_layers no)
			(net "P12V_BRICK")
			(clearance 0)
		)
		(pad "P5_7" thru_hole circle
			(at -5.08 38.1)
			(size 1.52781 1.52781)
			(drill 1.01981)
			(layers "*.Cu" "*.Mask")
			(remove_unused_layers no)
			(net "P12V_BRICK")
			(clearance 0)
		)
		(pad "P5_8" thru_hole circle
			(at -7.62 38.1)
			(size 1.52781 1.52781)
			(drill 1.01981)
			(layers "*.Cu" "*.Mask")
			(remove_unused_layers no)
			(net "P12V_BRICK")
			(clearance 0)
		)
		(pad "P6_1" thru_hole circle
			(at 0 44.45)
			(size 1.52781 1.52781)
			(drill 1.01981)
			(layers "*.Cu" "*.Mask")
			(remove_unused_layers no)
			(net "P12V_BRICK")
			(clearance 0)
		)
		(pad "P6_2" thru_hole circle
			(at -2.54 44.45)
			(size 1.52781 1.52781)
			(drill 1.01981)
			(layers "*.Cu" "*.Mask")
			(remove_unused_layers no)
			(net "P12V_BRICK")
			(clearance 0)
		)
		(pad "P6_3" thru_hole circle
			(at -5.08 44.45)
			(size 1.52781 1.52781)
			(drill 1.01981)
			(layers "*.Cu" "*.Mask")
			(remove_unused_layers no)
			(net "P12V_BRICK")
			(clearance 0)
		)
		(pad "P6_4" thru_hole circle
			(at -7.62 44.45)
			(size 1.52781 1.52781)
			(drill 1.01981)
			(layers "*.Cu" "*.Mask")
			(remove_unused_layers no)
			(net "P12V_BRICK")
			(clearance 0)
		)
		(pad "P6_5" thru_hole circle
			(at 0 46.99)
			(size 1.52781 1.52781)
			(drill 1.01981)
			(layers "*.Cu" "*.Mask")
			(remove_unused_layers no)
			(net "P12V_BRICK")
			(clearance 0)
		)
		(pad "P6_6" thru_hole circle
			(at -2.54 46.99)
			(size 1.52781 1.52781)
			(drill 1.01981)
			(layers "*.Cu" "*.Mask")
			(remove_unused_layers no)
			(net "P12V_BRICK")
			(clearance 0)
		)
		(pad "P6_7" thru_hole circle
			(at -5.08 46.99)
			(size 1.52781 1.52781)
			(drill 1.01981)
			(layers "*.Cu" "*.Mask")
			(remove_unused_layers no)
			(net "P12V_BRICK")
			(clearance 0)
		)
		(pad "P6_8" thru_hole circle
			(at -7.62 46.99)
			(size 1.52781 1.52781)
			(drill 1.01981)
			(layers "*.Cu" "*.Mask")
			(remove_unused_layers no)
			(net "P12V_BRICK")
			(clearance 0)
		)
		(zone
			(layers "F.Cu" "B.Cu" "In1.Cu" "In2.Cu" "In3.Cu" "In4.Cu" "In5.Cu" "In6.Cu"
				"In7.Cu" "In8.Cu"
			)
			(hatch none 0.5)
			(connect_pads
				(clearance 0)
			)
			(min_thickness 0.25)
			(keepout
				(tracks not_allowed)
				(vias allowed)
				(pads allowed)
				(copperpour not_allowed)
				(footprints allowed)
			)
			(placement
				(enabled no)
				(sheetname "")
			)
			(fill
				(thermal_gap 0.5)
				(thermal_bridge_width 0.5)
				(island_removal_mode 0)
			)
			(polygon
				(pts
					(arc
						(start 66.942208 -32.93999)
						(mid 59.677808 -32.93999)
						(end 66.942208 -32.93999)
					)
				)
			)
		)
		(zone
			(layers "F.Cu" "B.Cu" "In1.Cu" "In2.Cu" "In3.Cu" "In4.Cu" "In5.Cu" "In6.Cu"
				"In7.Cu" "In8.Cu"
			)
			(hatch none 0.5)
			(connect_pads
				(clearance 0)
			)
			(min_thickness 0.25)
			(keepout
				(tracks not_allowed)
				(vias allowed)
				(pads allowed)
				(copperpour not_allowed)
				(footprints allowed)
			)
			(placement
				(enabled no)
				(sheetname "")
			)
			(fill
				(thermal_gap 0.5)
				(thermal_bridge_width 0.5)
				(island_removal_mode 0)
			)
			(polygon
				(pts
					(arc
						(start 138.062208 -32.93999)
						(mid 130.797808 -32.93999)
						(end 138.062208 -32.93999)
					)
				)
			)
		)
		(zone
			(layer "B.Cu")
			(hatch none 0.5)
			(connect_pads
				(clearance 0)
			)
			(min_thickness 0.25)
			(keepout
				(tracks allowed)
				(vias not_allowed)
				(pads allowed)
				(copperpour not_allowed)
				(footprints allowed)
			)
			(placement
				(enabled no)
				(sheetname "")
			)
			(fill
				(thermal_gap 0.5)
				(thermal_bridge_width 0.5)
				(island_removal_mode 0)
			)
			(polygon
				(pts
					(xy 123.192286 -32.112712) (xy 123.192286 -41.387268) (xy 74.54773 -41.387268) (xy 74.54773 -32.112712)
				)
			)
		)
	)
)
